(kicad_pcb
	(version 20260206)
	(generator "pcbnew")
	(generator_version "10.0")
	(general
		(thickness 1.6)
		(legacy_teardrops no)
	)
	(paper "A4")
	(title_block
		(title "timecard-production-celestica-r4006 — R4006-B0001-02_R01.brd")
		(comment 1 "Time Appliance Project (Time Card) / footprints 637-643 of 1113")
	)
	(layers
		(0 "F.Cu" signal "TOP")
		(4 "In1.Cu" signal "L02_GND1")
		(6 "In2.Cu" signal "L03_SIG1")
		(8 "In3.Cu" signal "L04_GND2")
		(10 "In4.Cu" signal "L05_VCC1")
		(12 "In5.Cu" signal "L06_VCC2")
		(14 "In6.Cu" signal "L07_GND3")
		(16 "In7.Cu" signal "L08_SIG2")
		(18 "In8.Cu" signal "L09_GND4")
		(2 "B.Cu" signal "BOTTOM")
		(9 "F.Adhes" user "F.Adhesive")
		(11 "B.Adhes" user "B.Adhesive")
		(13 "F.Paste" user "Package Geometry/Pastemask Top")
		(15 "B.Paste" user "Package Geometry/Pastemask Bottom")
		(5 "F.SilkS" user "Ref Des/Silkscreen Top")
		(7 "B.SilkS" user "Ref Des/Silkscreen Bottom")
		(1 "F.Mask" user "Board Geometry/Soldermask Top")
		(3 "B.Mask" user "Board Geometry/Soldermask Bottom")
		(17 "Dwgs.User" user "User.Drawings")
		(19 "Cmts.User" user "User.Comments")
		(21 "Eco1.User" user "User.Eco1")
		(23 "Eco2.User" user "User.Eco2")
		(25 "Edge.Cuts" user "Board Geometry/Outline")
		(27 "Margin" user)
		(31 "F.CrtYd" user "Package Geometry/Place Bound Top")
		(29 "B.CrtYd" user "Package Geometry/Place Bound Bottom")
		(35 "F.Fab" user "Ref Des/Assembly Top")
		(33 "B.Fab" user "Ref Des/Assembly Bottom")
	)
	(footprint ""
		(layer "F.Cu")
		(at 95.504 -61.087 90)
		(property "Reference" "R164"
			(at -2.667 -0.08763 90)
			(unlocked yes)
			(layer "F.SilkS")
			(effects
				(font
					(size 0.7874 0.5842)
					(thickness 0.1524)
				)
			)
		)
		(property "Value" "VAL*"
			(at 0.02032 2.13233 90)
			(unlocked yes)
			(layer "F.Fab")
			(hide yes)
			(effects
				(font
					(size 0.7874 0.5842)
					(thickness 0.1524)
				)
			)
		)
		(property "Tolerance" "TOL*"
			(at 0.044704 3.05435 90)
			(unlocked yes)
			(layer "Cmts.User")
			(hide yes)
			(effects
				(font
					(size 0.7874 0.5842)
					(thickness 0.1524)
				)
			)
		)
		(property "User Part Number" "PARTNUM*"
			(at 0.02032 4.024884 90)
			(unlocked yes)
			(layer "Cmts.User")
			(hide yes)
			(effects
				(font
					(size 0.7874 0.5842)
					(thickness 0.1524)
				)
			)
		)
		(property "Device Type" "RESISTOR-G155-11003-01,100KOHMA"
			(at 0.008382 1.210564 90)
			(unlocked yes)
			(layer "F.Fab")
			(hide yes)
			(effects
				(font
					(size 0.7874 0.5842)
					(thickness 0.1524)
				)
			)
		)
		(duplicate_pad_numbers_are_jumpers no)
		(fp_line
			(start 1.143 -0.5588)
			(end -1.143 -0.5588)
			(stroke
				(width 0.1)
				(type default)
			)
			(layer "F.SilkS")
		)
		(fp_line
			(start -1.143 -0.5588)
			(end -1.143 0.5588)
			(stroke
				(width 0.1)
				(type default)
			)
			(layer "F.SilkS")
		)
		(fp_line
			(start 1.143 0.5588)
			(end 1.143 -0.5588)
			(stroke
				(width 0.1)
				(type default)
			)
			(layer "F.SilkS")
		)
		(fp_line
			(start -1.143 0.5588)
			(end 1.143 0.5588)
			(stroke
				(width 0.1)
				(type default)
			)
			(layer "F.SilkS")
		)
		(fp_poly
			(pts
				(xy -1.143 0.5588) (xy 1.143 0.5588) (xy 1.143 -0.5588) (xy -1.143 -0.5588)
			)
			(stroke
				(width 0)
				(type default)
			)
			(fill no)
			(layer "F.CrtYd")
		)
		(fp_line
			(start 0.508 -0.3048)
			(end -0.508 -0.3048)
			(stroke
				(width 0.1)
				(type default)
			)
			(layer "F.Fab")
		)
		(fp_line
			(start -0.508 -0.3048)
			(end -0.508 0.3048)
			(stroke
				(width 0.1)
				(type default)
			)
			(layer "F.Fab")
		)
		(fp_line
			(start 0.508 0.3048)
			(end 0.508 -0.3048)
			(stroke
				(width 0.1)
				(type default)
			)
			(layer "F.Fab")
		)
		(fp_line
			(start -0.508 0.3048)
			(end 0.508 0.3048)
			(stroke
				(width 0.1)
				(type default)
			)
			(layer "F.Fab")
		)
		(pad "1" smd rect
			(at -0.5334 0 90)
			(size 0.7112 0.6096)
			(layers "F.Cu" "F.Mask" "F.Paste")
			(net "XP3R3V_FPGA")
		)
		(pad "2" smd rect
			(at 0.5334 0 90)
			(size 0.7112 0.6096)
			(layers "F.Cu" "F.Mask" "F.Paste")
			(net "UNNAMED_3_RESISTOR_I151_2")
		)
		(zone
			(layer "F.Cu")
			(hatch none 0.5)
			(connect_pads
				(clearance 0)
			)
			(min_thickness 0.25)
			(keepout
				(tracks allowed)
				(vias not_allowed)
				(pads allowed)
				(copperpour not_allowed)
				(footprints allowed)
			)
			(placement
				(enabled no)
				(sheetname "")
			)
			(fill
				(thermal_gap 0.5)
				(thermal_bridge_width 0.5)
				(island_removal_mode 0)
			)
			(polygon
				(pts
					(xy 95.8088 -61.0108) (xy 95.8088 -61.1632) (xy 95.1992 -61.1632) (xy 95.1992 -61.0108)
				)
			)
		)
		(zone
			(layer "F.Cu")
			(hatch none 0.5)
			(connect_pads
				(clearance 0)
			)
			(min_thickness 0.25)
			(keepout
				(tracks not_allowed)
				(vias allowed)
				(pads allowed)
				(copperpour not_allowed)
				(footprints allowed)
			)
			(placement
				(enabled no)
				(sheetname "")
			)
			(fill
				(thermal_gap 0.5)
				(thermal_bridge_width 0.5)
				(island_removal_mode 0)
			)
			(polygon
				(pts
					(xy 95.8088 -61.0108) (xy 95.8088 -61.1632) (xy 95.1992 -61.1632) (xy 95.1992 -61.0108)
				)
			)
		)
	)
	(footprint ""
		(layer "F.Cu")
		(at 138.43 -53.594 -90)
		(property "Reference" "C261"
			(at 0.508 3.26263 90)
			(unlocked yes)
			(layer "F.SilkS")
			(effects
				(font
					(size 0.7874 0.5842)
					(thickness 0.1524)
				)
			)
		)
		(property "Value" "VAL*"
			(at 0.0762 2.067306 270)
			(unlocked yes)
			(layer "F.Fab")
			(hide yes)
			(effects
				(font
					(size 0.7874 0.5842)
					(thickness 0.1524)
				)
			)
		)
		(property "Device Type" "CAPACITOR-G105-0B104-EK,0.1UF,A"
			(at 0.0508 1.127506 270)
			(unlocked yes)
			(layer "F.Fab")
			(hide yes)
			(effects
				(font
					(size 0.7874 0.5842)
					(thickness 0.1524)
				)
			)
		)
		(property "User Part Number" "PARTNUM*"
			(at 0.1016 4.023106 270)
			(unlocked yes)
			(layer "Cmts.User")
			(hide yes)
			(effects
				(font
					(size 0.7874 0.5842)
					(thickness 0.1524)
				)
			)
		)
		(property "Tolerance" "TOL*"
			(at 0.0762 3.032506 270)
			(unlocked yes)
			(layer "Cmts.User")
			(hide yes)
			(effects
				(font
					(size 0.7874 0.5842)
					(thickness 0.1524)
				)
			)
		)
		(duplicate_pad_numbers_are_jumpers no)
		(fp_line
			(start -1.143 0.5588)
			(end 1.143 0.5588)
			(stroke
				(width 0.1)
				(type default)
			)
			(layer "F.SilkS")
		)
		(fp_line
			(start 1.143 0.5588)
			(end 1.143 -0.5588)
			(stroke
				(width 0.1)
				(type default)
			)
			(layer "F.SilkS")
		)
		(fp_line
			(start -1.143 -0.5588)
			(end -1.143 0.5588)
			(stroke
				(width 0.1)
				(type default)
			)
			(layer "F.SilkS")
		)
		(fp_line
			(start 1.143 -0.5588)
			(end -1.143 -0.5588)
			(stroke
				(width 0.1)
				(type default)
			)
			(layer "F.SilkS")
		)
		(fp_rect
			(start 1.143 0.5588)
			(end -1.143 -0.5588)
			(stroke
				(width 0)
				(type default)
			)
			(fill no)
			(layer "F.CrtYd")
		)
		(fp_line
			(start -0.508 0.3048)
			(end 0.508 0.3048)
			(stroke
				(width 0.1)
				(type default)
			)
			(layer "F.Fab")
		)
		(fp_line
			(start 0.508 0.3048)
			(end 0.508 -0.3048)
			(stroke
				(width 0.1)
				(type default)
			)
			(layer "F.Fab")
		)
		(fp_line
			(start -0.508 -0.3048)
			(end -0.508 0.3048)
			(stroke
				(width 0.1)
				(type default)
			)
			(layer "F.Fab")
		)
		(fp_line
			(start 0.508 -0.3048)
			(end -0.508 -0.3048)
			(stroke
				(width 0.1)
				(type default)
			)
			(layer "F.Fab")
		)
		(pad "1" smd rect
			(at -0.5334 0 270)
			(size 0.7112 0.6096)
			(layers "F.Cu" "F.Mask" "F.Paste")
			(net "VIN_XP1R0V")
		)
		(pad "2" smd rect
			(at 0.5334 0 270)
			(size 0.7112 0.6096)
			(layers "F.Cu" "F.Mask" "F.Paste")
			(net "SG")
		)
		(zone
			(layer "F.Cu")
			(hatch none 0.5)
			(connect_pads
				(clearance 0)
			)
			(min_thickness 0.25)
			(keepout
				(tracks allowed)
				(vias not_allowed)
				(pads allowed)
				(copperpour not_allowed)
				(footprints allowed)
			)
			(placement
				(enabled no)
				(sheetname "")
			)
			(fill
				(thermal_gap 0.5)
				(thermal_bridge_width 0.5)
				(island_removal_mode 0)
			)
			(polygon
				(pts
					(xy 138.1252 -53.5178) (xy 138.7348 -53.5178) (xy 138.7348 -53.6702) (xy 138.1252 -53.6702)
				)
			)
		)
	)
	(footprint ""
		(layer "F.Cu")
		(at 123.19 -39.116)
		(property "Reference" "TP136"
			(at -0.73025 0.8128 90)
			(unlocked yes)
			(layer "F.SilkS")
			(effects
				(font
					(size 0.635 0.4064)
					(thickness 0.1524)
				)
				(justify left)
			)
		)
		(property "Value" ""
			(at 0 0 0)
			(layer "F.Fab")
			(effects
				(font
					(size 1.27 1.27)
				)
			)
		)
		(property "Device Type" "TP_PIONT-TP010CT020B030_PTH-TPA"
			(at -1.341882 0.996696 0)
			(unlocked yes)
			(layer "F.Fab")
			(hide yes)
			(effects
				(font
					(size 0.7874 0.5842)
					(thickness 0.1524)
				)
				(justify left)
			)
		)
		(duplicate_pad_numbers_are_jumpers no)
		(fp_poly
			(pts
				(arc
					(start 0.889 0)
					(mid -0.889 0)
					(end 0.889 0)
				)
			)
			(stroke
				(width 0)
				(type default)
			)
			(fill no)
			(layer "B.CrtYd")
		)
		(fp_poly
			(pts
				(arc
					(start 0.889 0)
					(mid -0.889 0)
					(end 0.889 0)
				)
			)
			(stroke
				(width 0)
				(type default)
			)
			(fill no)
			(layer "F.CrtYd")
		)
		(pad "1" thru_hole circle
			(at 0 0)
			(size 0.508 0.508)
			(drill 0.254)
			(layers "*.Cu" "*.Mask")
			(remove_unused_layers no)
			(net "IO_L22P_34")
			(clearance 0.1016)
			(padstack
				(mode front_inner_back)
				(layer "Inner"
					(shape circle)
					(size 0.508 0.508)
					(clearance 0.1016)
				)
				(layer "B.Cu"
					(shape circle)
					(size 0.762 0.762)
					(clearance -0.0254)
				)
			)
		)
	)
	(footprint ""
		(layer "F.Cu")
		(at 133.223 -34.163)
		(property "Reference" "C176"
			(at 4.445 1.94437 0)
			(unlocked yes)
			(layer "F.SilkS")
			(effects
				(font
					(size 0.7874 0.5842)
					(thickness 0.1524)
				)
			)
		)
		(property "Value" "VAL*"
			(at 0.1016 3.769106 0)
			(unlocked yes)
			(layer "F.Fab")
			(hide yes)
			(effects
				(font
					(size 0.7874 0.5842)
					(thickness 0.1524)
				)
			)
		)
		(property "Tolerance" "TOL*"
			(at 0.127 4.734306 0)
			(unlocked yes)
			(layer "Cmts.User")
			(hide yes)
			(effects
				(font
					(size 0.7874 0.5842)
					(thickness 0.1524)
				)
			)
		)
		(property "User Part Number" "PARTNUM*"
			(at 0.2032 5.801106 0)
			(unlocked yes)
			(layer "Cmts.User")
			(hide yes)
			(effects
				(font
					(size 0.7874 0.5842)
					(thickness 0.1524)
				)
			)
		)
		(property "Device Type" "CAPACITOR-G109-0G107-BM,100UF,A"
			(at 0.0762 2.829306 0)
			(unlocked yes)
			(layer "F.Fab")
			(hide yes)
			(effects
				(font
					(size 0.7874 0.5842)
					(thickness 0.1524)
				)
			)
		)
		(duplicate_pad_numbers_are_jumpers no)
		(fp_line
			(start -2.159 -1.5748)
			(end 2.159 -1.5748)
			(stroke
				(width 0.1)
				(type default)
			)
			(layer "F.SilkS")
		)
		(fp_line
			(start -2.159 1.5748)
			(end -2.159 -1.5748)
			(stroke
				(width 0.1)
				(type default)
			)
			(layer "F.SilkS")
		)
		(fp_line
			(start 2.159 -1.5748)
			(end 2.159 1.5748)
			(stroke
				(width 0.1)
				(type default)
			)
			(layer "F.SilkS")
		)
		(fp_line
			(start 2.159 1.5748)
			(end -2.159 1.5748)
			(stroke
				(width 0.1)
				(type default)
			)
			(layer "F.SilkS")
		)
		(fp_rect
			(start 2.159 1.5748)
			(end -2.159 -1.5748)
			(stroke
				(width 0)
				(type default)
			)
			(fill no)
			(layer "F.CrtYd")
		)
		(fp_line
			(start -1.6002 -1.2446)
			(end -1.6002 1.2446)
			(stroke
				(width 0.1)
				(type default)
			)
			(layer "F.Fab")
		)
		(fp_line
			(start -1.6002 1.2446)
			(end 1.6002 1.2446)
			(stroke
				(width 0.1)
				(type default)
			)
			(layer "F.Fab")
		)
		(fp_line
			(start 1.6002 -1.2446)
			(end -1.6002 -1.2446)
			(stroke
				(width 0.1)
				(type default)
			)
			(layer "F.Fab")
		)
		(fp_line
			(start 1.6002 1.2446)
			(end 1.6002 -1.2446)
			(stroke
				(width 0.1)
				(type default)
			)
			(layer "F.Fab")
		)
		(pad "1" smd rect
			(at -1.3335 0)
			(size 1.143 2.6416)
			(layers "F.Cu" "F.Mask" "F.Paste")
			(net "XP1R0V_FPGA_VCCINT")
		)
		(pad "2" smd rect
			(at 1.3335 0)
			(size 1.143 2.6416)
			(layers "F.Cu" "F.Mask" "F.Paste")
			(net "SG")
		)
		(zone
			(layer "F.Cu")
			(hatch none 0.5)
			(connect_pads
				(clearance 0)
			)
			(min_thickness 0.25)
			(keepout
				(tracks allowed)
				(vias not_allowed)
				(pads allowed)
				(copperpour not_allowed)
				(footprints allowed)
			)
			(placement
				(enabled no)
				(sheetname "")
			)
			(fill
				(thermal_gap 0.5)
				(thermal_bridge_width 0.5)
				(island_removal_mode 0)
			)
			(polygon
				(pts
					(xy 133.9088 -32.766) (xy 133.9088 -35.56) (xy 132.5372 -35.56) (xy 132.5372 -32.766)
				)
			)
		)
	)
	(footprint ""
		(layer "F.Cu")
		(at 90.9828 -70.6628 -90)
		(property "Reference" "C198"
			(at -18.6182 27.44343 90)
			(unlocked yes)
			(layer "F.SilkS")
			(effects
				(font
					(size 0.7874 0.5842)
					(thickness 0.1524)
				)
			)
		)
		(property "Value" "VAL*"
			(at 0.02032 2.13233 270)
			(unlocked yes)
			(layer "F.Fab")
			(hide yes)
			(effects
				(font
					(size 0.7874 0.5842)
					(thickness 0.1524)
				)
			)
		)
		(property "Tolerance" "TOL*"
			(at 0.044704 3.05435 270)
			(unlocked yes)
			(layer "Cmts.User")
			(hide yes)
			(effects
				(font
					(size 0.7874 0.5842)
					(thickness 0.1524)
				)
			)
		)
		(property "User Part Number" "PARTNUM*"
			(at 0.02032 4.024884 270)
			(unlocked yes)
			(layer "Cmts.User")
			(hide yes)
			(effects
				(font
					(size 0.7874 0.5842)
					(thickness 0.1524)
				)
			)
		)
		(property "Device Type" "CAPACITOR-G105-0F475-BM,4.7UF,A"
			(at 0.008382 1.210564 270)
			(unlocked yes)
			(layer "F.Fab")
			(hide yes)
			(effects
				(font
					(size 0.7874 0.5842)
					(thickness 0.1524)
				)
			)
		)
		(duplicate_pad_numbers_are_jumpers no)
		(fp_line
			(start -1.143 0.5588)
			(end 1.143 0.5588)
			(stroke
				(width 0.1)
				(type default)
			)
			(layer "F.SilkS")
		)
		(fp_line
			(start 1.143 0.5588)
			(end 1.143 -0.5588)
			(stroke
				(width 0.1)
				(type default)
			)
			(layer "F.SilkS")
		)
		(fp_line
			(start -1.143 -0.5588)
			(end -1.143 0.5588)
			(stroke
				(width 0.1)
				(type default)
			)
			(layer "F.SilkS")
		)
		(fp_line
			(start 1.143 -0.5588)
			(end -1.143 -0.5588)
			(stroke
				(width 0.1)
				(type default)
			)
			(layer "F.SilkS")
		)
		(fp_rect
			(start 1.143 0.5588)
			(end -1.143 -0.5588)
			(stroke
				(width 0)
				(type default)
			)
			(fill no)
			(layer "F.CrtYd")
		)
		(fp_line
			(start -0.508 0.3048)
			(end 0.508 0.3048)
			(stroke
				(width 0.1)
				(type default)
			)
			(layer "F.Fab")
		)
		(fp_line
			(start 0.508 0.3048)
			(end 0.508 -0.3048)
			(stroke
				(width 0.1)
				(type default)
			)
			(layer "F.Fab")
		)
		(fp_line
			(start -0.508 -0.3048)
			(end -0.508 0.3048)
			(stroke
				(width 0.1)
				(type default)
			)
			(layer "F.Fab")
		)
		(fp_line
			(start 0.508 -0.3048)
			(end -0.508 -0.3048)
			(stroke
				(width 0.1)
				(type default)
			)
			(layer "F.Fab")
		)
		(pad "1" smd rect
			(at -0.5334 0 270)
			(size 0.7112 0.6096)
			(layers "F.Cu" "F.Mask" "F.Paste")
			(net "XP3R3V_FPGA")
		)
		(pad "2" smd rect
			(at 0.5334 0 270)
			(size 0.7112 0.6096)
			(layers "F.Cu" "F.Mask" "F.Paste")
			(net "SG")
		)
		(zone
			(layer "F.Cu")
			(hatch none 0.5)
			(connect_pads
				(clearance 0)
			)
			(min_thickness 0.25)
			(keepout
				(tracks allowed)
				(vias not_allowed)
				(pads allowed)
				(copperpour not_allowed)
				(footprints allowed)
			)
			(placement
				(enabled no)
				(sheetname "")
			)
			(fill
				(thermal_gap 0.5)
				(thermal_bridge_width 0.5)
				(island_removal_mode 0)
			)
			(polygon
				(pts
					(xy 90.678 -70.5866) (xy 91.2876 -70.5866) (xy 91.2876 -70.739) (xy 90.678 -70.739)
				)
			)
		)
	)
	(footprint ""
		(layer "F.Cu")
		(at 23.608792 -68.1482)
		(property "Reference" "C278"
			(at 3.315208 -0.01143 0)
			(unlocked yes)
			(layer "F.SilkS")
			(effects
				(font
					(size 0.7874 0.5842)
					(thickness 0.1524)
				)
			)
		)
		(property "Value" "VAL*"
			(at 0.0762 2.067306 0)
			(unlocked yes)
			(layer "F.Fab")
			(hide yes)
			(effects
				(font
					(size 0.7874 0.5842)
					(thickness 0.1524)
				)
			)
		)
		(property "Tolerance" "TOL*"
			(at 0.0762 3.032506 0)
			(unlocked yes)
			(layer "Cmts.User")
			(hide yes)
			(effects
				(font
					(size 0.7874 0.5842)
					(thickness 0.1524)
				)
			)
		)
		(property "User Part Number" "PARTNUM*"
			(at 0.1016 4.023106 0)
			(unlocked yes)
			(layer "Cmts.User")
			(hide yes)
			(effects
				(font
					(size 0.7874 0.5842)
					(thickness 0.1524)
				)
			)
		)
		(property "Device Type" "CAPACITOR-G105-0B104-EK,0.1UF,A"
			(at 0.0508 1.127506 0)
			(unlocked yes)
			(layer "F.Fab")
			(hide yes)
			(effects
				(font
					(size 0.7874 0.5842)
					(thickness 0.1524)
				)
			)
		)
		(duplicate_pad_numbers_are_jumpers no)
		(fp_line
			(start -1.143 -0.5588)
			(end -1.143 0.5588)
			(stroke
				(width 0.1)
				(type default)
			)
			(layer "F.SilkS")
		)
		(fp_line
			(start -1.143 0.5588)
			(end 1.143 0.5588)
			(stroke
				(width 0.1)
				(type default)
			)
			(layer "F.SilkS")
		)
		(fp_line
			(start 1.143 -0.5588)
			(end -1.143 -0.5588)
			(stroke
				(width 0.1)
				(type default)
			)
			(layer "F.SilkS")
		)
		(fp_line
			(start 1.143 0.5588)
			(end 1.143 -0.5588)
			(stroke
				(width 0.1)
				(type default)
			)
			(layer "F.SilkS")
		)
		(fp_rect
			(start -1.143 -0.5588)
			(end 1.143 0.5588)
			(stroke
				(width 0)
				(type default)
			)
			(fill no)
			(layer "F.CrtYd")
		)
		(fp_line
			(start -0.508 -0.3048)
			(end -0.508 0.3048)
			(stroke
				(width 0.1)
				(type default)
			)
			(layer "F.Fab")
		)
		(fp_line
			(start -0.508 0.3048)
			(end 0.508 0.3048)
			(stroke
				(width 0.1)
				(type default)
			)
			(layer "F.Fab")
		)
		(fp_line
			(start 0.508 -0.3048)
			(end -0.508 -0.3048)
			(stroke
				(width 0.1)
				(type default)
			)
			(layer "F.Fab")
		)
		(fp_line
			(start 0.508 0.3048)
			(end 0.508 -0.3048)
			(stroke
				(width 0.1)
				(type default)
			)
			(layer "F.Fab")
		)
		(pad "1" smd rect
			(at -0.5334 0)
			(size 0.7112 0.6096)
			(layers "F.Cu" "F.Mask" "F.Paste")
			(net "XP1R8V_ICP10100")
		)
		(pad "2" smd rect
			(at 0.5334 0)
			(size 0.7112 0.6096)
			(layers "F.Cu" "F.Mask" "F.Paste")
			(net "SG")
		)
		(zone
			(layer "F.Cu")
			(hatch none 0.5)
			(connect_pads
				(clearance 0)
			)
			(min_thickness 0.25)
			(keepout
				(tracks allowed)
				(vias not_allowed)
				(pads allowed)
				(copperpour not_allowed)
				(footprints allowed)
			)
			(placement
				(enabled no)
				(sheetname "")
			)
			(fill
				(thermal_gap 0.5)
				(thermal_bridge_width 0.5)
				(island_removal_mode 0)
			)
			(polygon
				(pts
					(xy 23.532592 -68.453) (xy 23.532592 -67.8434) (xy 23.684992 -67.8434) (xy 23.684992 -68.453)
				)
			)
		)
	)
	(footprint ""
		(layer "F.Cu")
		(at 63.881 -135.509)
		(property "Reference" "SP47"
			(at 0 0 0)
			(layer "F.SilkS")
			(hide yes)
			(effects
				(font
					(size 1.27 1.27)
				)
			)
		)
		(property "Value" ""
			(at 0 0 0)
			(layer "F.Fab")
			(effects
				(font
					(size 1.27 1.27)
				)
			)
		)
		(duplicate_pad_numbers_are_jumpers no)
	)
)
